(kicad_pcb
	(version 20260206)
	(generator "pcbnew")
	(generator_version "10.0")
	(general
		(thickness 1.6)
		(legacy_teardrops no)
	)
	(paper "A4")
	(title_block
		(title "dpb — 14545-sa.0730WZS0815.brd")
		(comment 1 "Honey Badger (Wiwynn) / footprints 211-217 of 1066")
	)
	(layers
		(0 "F.Cu" signal "TOP")
		(4 "In1.Cu" signal "L2GND")
		(6 "In2.Cu" signal "L3")
		(8 "In3.Cu" signal "L4VCC")
		(10 "In4.Cu" signal "L5VCC")
		(12 "In5.Cu" signal "L6")
		(14 "In6.Cu" signal "L7GND")
		(2 "B.Cu" signal "BOTTOM")
		(9 "F.Adhes" user "F.Adhesive")
		(11 "B.Adhes" user "B.Adhesive")
		(13 "F.Paste" user "Package Geometry/Pastemask Top")
		(15 "B.Paste" user "Package Geometry/Pastemask Bottom")
		(5 "F.SilkS" user "Ref Des/Silkscreen Top")
		(7 "B.SilkS" user "Ref Des/Silkscreen Bottom")
		(1 "F.Mask" user "Board Geometry/Soldermask Top")
		(3 "B.Mask" user "Board Geometry/Soldermask Bottom")
		(17 "Dwgs.User" user "User.Drawings")
		(19 "Cmts.User" user "User.Comments")
		(21 "Eco1.User" user "User.Eco1")
		(23 "Eco2.User" user "User.Eco2")
		(25 "Edge.Cuts" user "Board Geometry/Outline")
		(27 "Margin" user)
		(31 "F.CrtYd" user "Package Geometry/Place Bound Top")
		(29 "B.CrtYd" user "Package Geometry/Place Bound Bottom")
		(35 "F.Fab" user "Ref Des/Assembly Top")
		(33 "B.Fab" user "Ref Des/Assembly Bottom")
	)
	(footprint ""
		(layer "F.Cu")
		(at 39.623746 -144.7927 90)
		(property "Reference" "R213"
			(at 0 0 90)
			(layer "F.SilkS")
			(hide yes)
			(effects
				(font
					(size 1.27 1.27)
				)
			)
		)
		(property "Value" "402R2F-GP"
			(at 0.064008 -3.993896 90)
			(unlocked yes)
			(layer "F.Fab")
			(hide yes)
			(effects
				(font
					(size 1.016 1.016)
					(thickness 0.1524)
				)
			)
		)
		(property "Device Type" "R402H16"
			(at 0.064008 -5.517896 90)
			(unlocked yes)
			(layer "F.Fab")
			(hide yes)
			(effects
				(font
					(size 1.016 1.016)
					(thickness 0.1524)
				)
			)
		)
		(duplicate_pad_numbers_are_jumpers no)
		(fp_line
			(start 0.508 -0.9398)
			(end -0.508 -0.9398)
			(stroke
				(width 0.1524)
				(type default)
			)
			(layer "F.SilkS")
		)
		(fp_line
			(start -0.508 -0.9398)
			(end -0.508 0.9398)
			(stroke
				(width 0.1524)
				(type default)
			)
			(layer "F.SilkS")
		)
		(fp_rect
			(start -0.508 0.9398)
			(end 0.508 -0.9398)
			(stroke
				(width 0)
				(type default)
			)
			(fill no)
			(layer "F.CrtYd")
		)
		(fp_rect
			(start -0.508 0.9398)
			(end 0.508 -0.9398)
			(stroke
				(width 0)
				(type default)
			)
			(fill no)
			(layer "F.Fab")
		)
		(pad "1" smd custom
			(at 0 -0.4445 90)
			(size 0.1397 0.1397)
			(layers "F.Cu" "F.Mask" "F.Paste")
			(net "P5VB_HDD8_LED")
			(options
				(clearance outline)
				(anchor circle)
			)
			(primitives
				(gr_poly
					(pts
						(arc
							(start -0.1778 -0.2794)
							(mid -0.249642 -0.249642)
							(end -0.2794 -0.1778)
						)
						(arc
							(start -0.2794 0.1778)
							(mid -0.249642 0.249642)
							(end -0.1778 0.2794)
						)
						(arc
							(start 0.1778 0.2794)
							(mid 0.249642 0.249642)
							(end 0.2794 0.1778)
						)
						(arc
							(start 0.2794 -0.1778)
							(mid 0.249642 -0.249642)
							(end 0.1778 -0.2794)
						)
					)
					(width 0)
					(fill yes)
				)
			)
		)
		(pad "2" smd custom
			(at 0 0.4445 90)
			(size 0.1397 0.1397)
			(layers "F.Cu" "F.Mask" "F.Paste")
			(net "DRV_ACT_8")
			(options
				(clearance outline)
				(anchor circle)
			)
			(primitives
				(gr_poly
					(pts
						(arc
							(start -0.1778 -0.2794)
							(mid -0.249642 -0.249642)
							(end -0.2794 -0.1778)
						)
						(arc
							(start -0.2794 0.1778)
							(mid -0.249642 0.249642)
							(end -0.1778 0.2794)
						)
						(arc
							(start 0.1778 0.2794)
							(mid 0.249642 0.249642)
							(end 0.2794 0.1778)
						)
						(arc
							(start 0.2794 -0.1778)
							(mid 0.249642 -0.249642)
							(end 0.1778 -0.2794)
						)
					)
					(width 0)
					(fill yes)
				)
			)
		)
	)
	(footprint ""
		(layer "F.Cu")
		(at 33.273746 -263.0297 -90)
		(property "Reference" "C214"
			(at 0 0 270)
			(layer "F.SilkS")
			(hide yes)
			(effects
				(font
					(size 1.27 1.27)
				)
			)
		)
		(property "Value" "SCD01U50V2KX-1GP"
			(at 1.1811 -2.7051 270)
			(unlocked yes)
			(layer "F.Fab")
			(hide yes)
			(effects
				(font
					(size 1.016 1.016)
					(thickness 0.1524)
				)
			)
		)
		(property "Device Type" "C402H22"
			(at 1.1811 -4.2291 270)
			(unlocked yes)
			(layer "F.Fab")
			(hide yes)
			(effects
				(font
					(size 1.016 1.016)
					(thickness 0.1524)
				)
			)
		)
		(duplicate_pad_numbers_are_jumpers no)
		(fp_rect
			(start -0.4318 0.9525)
			(end 0.4318 -0.9525)
			(stroke
				(width 0)
				(type default)
			)
			(fill no)
			(layer "F.CrtYd")
		)
		(fp_rect
			(start -0.4318 0.9525)
			(end 0.4318 -0.9525)
			(stroke
				(width 0)
				(type default)
			)
			(fill no)
			(layer "F.Fab")
		)
		(pad "1" smd custom
			(at 0 -0.4445 270)
			(size 0.1524 0.1524)
			(layers "F.Cu" "F.Mask" "F.Paste")
			(net "SAS2X28_DRIVE_RX_N_A7")
			(options
				(clearance outline)
				(anchor circle)
			)
			(primitives
				(gr_poly
					(pts
						(arc
							(start 0.3048 -0.2032)
							(mid 0.275042 -0.275042)
							(end 0.2032 -0.3048)
						)
						(arc
							(start -0.2032 -0.3048)
							(mid -0.275042 -0.275042)
							(end -0.3048 -0.2032)
						)
						(arc
							(start -0.3048 0.2032)
							(mid -0.275042 0.275042)
							(end -0.2032 0.3048)
						)
						(arc
							(start 0.2032 0.3048)
							(mid 0.275042 0.275042)
							(end 0.3048 0.2032)
						)
					)
					(width 0)
					(fill yes)
				)
			)
		)
		(pad "2" smd custom
			(at 0 0.4445 270)
			(size 0.1524 0.1524)
			(layers "F.Cu" "F.Mask" "F.Paste")
			(net "SAS2X28_A_HDD7_RX_-")
			(options
				(clearance outline)
				(anchor circle)
			)
			(primitives
				(gr_poly
					(pts
						(arc
							(start 0.3048 -0.2032)
							(mid 0.275042 -0.275042)
							(end 0.2032 -0.3048)
						)
						(arc
							(start -0.2032 -0.3048)
							(mid -0.275042 -0.275042)
							(end -0.3048 -0.2032)
						)
						(arc
							(start -0.3048 0.2032)
							(mid -0.275042 0.275042)
							(end -0.2032 0.3048)
						)
						(arc
							(start 0.2032 0.3048)
							(mid 0.275042 0.275042)
							(end 0.3048 0.2032)
						)
					)
					(width 0)
					(fill yes)
				)
			)
		)
	)
	(footprint ""
		(layer "F.Cu")
		(at 49.021746 -348.7547 90)
		(property "Reference" "R188"
			(at 0 0 90)
			(layer "F.SilkS")
			(hide yes)
			(effects
				(font
					(size 1.27 1.27)
				)
			)
		)
		(property "Value" "0R2J-2-GP"
			(at 0.064008 -3.993896 90)
			(unlocked yes)
			(layer "F.Fab")
			(hide yes)
			(effects
				(font
					(size 1.016 1.016)
					(thickness 0.1524)
				)
			)
		)
		(property "Device Type" "R402H16"
			(at 0.064008 -5.517896 90)
			(unlocked yes)
			(layer "F.Fab")
			(hide yes)
			(effects
				(font
					(size 1.016 1.016)
					(thickness 0.1524)
				)
			)
		)
		(duplicate_pad_numbers_are_jumpers no)
		(fp_line
			(start 0.508 -0.9398)
			(end -0.508 -0.9398)
			(stroke
				(width 0.1524)
				(type default)
			)
			(layer "F.SilkS")
		)
		(fp_line
			(start -0.508 -0.9398)
			(end -0.508 0.9398)
			(stroke
				(width 0.1524)
				(type default)
			)
			(layer "F.SilkS")
		)
		(fp_rect
			(start -0.508 0.9398)
			(end 0.508 -0.9398)
			(stroke
				(width 0)
				(type default)
			)
			(fill no)
			(layer "F.CrtYd")
		)
		(fp_rect
			(start -0.508 0.9398)
			(end 0.508 -0.9398)
			(stroke
				(width 0)
				(type default)
			)
			(fill no)
			(layer "F.Fab")
		)
		(pad "1" smd custom
			(at 0 -0.4445 90)
			(size 0.1397 0.1397)
			(layers "F.Cu" "F.Mask" "F.Paste")
			(net "FLT_NET_HDD6")
			(options
				(clearance outline)
				(anchor circle)
			)
			(primitives
				(gr_poly
					(pts
						(arc
							(start -0.1778 -0.2794)
							(mid -0.249642 -0.249642)
							(end -0.2794 -0.1778)
						)
						(arc
							(start -0.2794 0.1778)
							(mid -0.249642 0.249642)
							(end -0.1778 0.2794)
						)
						(arc
							(start 0.1778 0.2794)
							(mid 0.249642 0.249642)
							(end 0.2794 0.1778)
						)
						(arc
							(start 0.2794 -0.1778)
							(mid 0.249642 -0.249642)
							(end 0.1778 -0.2794)
						)
					)
					(width 0)
					(fill yes)
				)
			)
		)
		(pad "2" smd custom
			(at 0 0.4445 90)
			(size 0.1397 0.1397)
			(layers "F.Cu" "F.Mask" "F.Paste")
			(net "FLT_HDD6_DRIVE")
			(options
				(clearance outline)
				(anchor circle)
			)
			(primitives
				(gr_poly
					(pts
						(arc
							(start -0.1778 -0.2794)
							(mid -0.249642 -0.249642)
							(end -0.2794 -0.1778)
						)
						(arc
							(start -0.2794 0.1778)
							(mid -0.249642 0.249642)
							(end -0.1778 0.2794)
						)
						(arc
							(start 0.1778 0.2794)
							(mid 0.249642 0.249642)
							(end 0.2794 0.1778)
						)
						(arc
							(start 0.2794 -0.1778)
							(mid 0.249642 -0.249642)
							(end 0.1778 -0.2794)
						)
					)
					(width 0)
					(fill yes)
				)
			)
		)
	)
	(footprint ""
		(layer "F.Cu")
		(at 197.357746 -286.3977 -90)
		(property "Reference" "R432"
			(at 0 0 270)
			(layer "F.SilkS")
			(hide yes)
			(effects
				(font
					(size 1.27 1.27)
				)
			)
		)
		(property "Value" "4K7R2J-2-GP"
			(at 0.064008 -3.993896 270)
			(unlocked yes)
			(layer "F.Fab")
			(hide yes)
			(effects
				(font
					(size 1.016 1.016)
					(thickness 0.1524)
				)
			)
		)
		(property "Device Type" "R402H16"
			(at 0.064008 -5.517896 270)
			(unlocked yes)
			(layer "F.Fab")
			(hide yes)
			(effects
				(font
					(size 1.016 1.016)
					(thickness 0.1524)
				)
			)
		)
		(duplicate_pad_numbers_are_jumpers no)
		(fp_line
			(start -0.508 -0.9398)
			(end -0.508 0.9398)
			(stroke
				(width 0.1524)
				(type default)
			)
			(layer "F.SilkS")
		)
		(fp_line
			(start 0.508 -0.9398)
			(end -0.508 -0.9398)
			(stroke
				(width 0.1524)
				(type default)
			)
			(layer "F.SilkS")
		)
		(fp_rect
			(start -0.508 0.9398)
			(end 0.508 -0.9398)
			(stroke
				(width 0)
				(type default)
			)
			(fill no)
			(layer "F.CrtYd")
		)
		(fp_rect
			(start -0.508 0.9398)
			(end 0.508 -0.9398)
			(stroke
				(width 0)
				(type default)
			)
			(fill no)
			(layer "F.Fab")
		)
		(pad "1" smd custom
			(at 0 -0.4445 270)
			(size 0.1397 0.1397)
			(layers "F.Cu" "F.Mask" "F.Paste")
			(net "P3V3")
			(options
				(clearance outline)
				(anchor circle)
			)
			(primitives
				(gr_poly
					(pts
						(arc
							(start -0.1778 -0.2794)
							(mid -0.249642 -0.249642)
							(end -0.2794 -0.1778)
						)
						(arc
							(start -0.2794 0.1778)
							(mid -0.249642 0.249642)
							(end -0.1778 0.2794)
						)
						(arc
							(start 0.1778 0.2794)
							(mid 0.249642 0.249642)
							(end 0.2794 0.1778)
						)
						(arc
							(start 0.2794 -0.1778)
							(mid 0.249642 -0.249642)
							(end 0.1778 -0.2794)
						)
					)
					(width 0)
					(fill yes)
				)
			)
		)
		(pad "2" smd custom
			(at 0 0.4445 270)
			(size 0.1397 0.1397)
			(layers "F.Cu" "F.Mask" "F.Paste")
			(net "SAS_EXP_A_PWR2")
			(options
				(clearance outline)
				(anchor circle)
			)
			(primitives
				(gr_poly
					(pts
						(arc
							(start -0.1778 -0.2794)
							(mid -0.249642 -0.249642)
							(end -0.2794 -0.1778)
						)
						(arc
							(start -0.2794 0.1778)
							(mid -0.249642 0.249642)
							(end -0.1778 0.2794)
						)
						(arc
							(start 0.1778 0.2794)
							(mid 0.249642 0.249642)
							(end 0.2794 0.1778)
						)
						(arc
							(start 0.2794 -0.1778)
							(mid 0.249642 -0.249642)
							(end 0.1778 -0.2794)
						)
					)
					(width 0)
					(fill yes)
				)
			)
		)
	)
	(footprint ""
		(layer "F.Cu")
		(at 71.500746 -190.5127)
		(property "Reference" "R452"
			(at 0 0 0)
			(layer "F.SilkS")
			(hide yes)
			(effects
				(font
					(size 1.27 1.27)
				)
			)
		)
		(property "Value" "4K7R2J-2-GP"
			(at 0.064008 -3.993896 0)
			(unlocked yes)
			(layer "F.Fab")
			(hide yes)
			(effects
				(font
					(size 1.016 1.016)
					(thickness 0.1524)
				)
			)
		)
		(property "Device Type" "R402H16"
			(at 0.064008 -5.517896 0)
			(unlocked yes)
			(layer "F.Fab")
			(hide yes)
			(effects
				(font
					(size 1.016 1.016)
					(thickness 0.1524)
				)
			)
		)
		(duplicate_pad_numbers_are_jumpers no)
		(fp_line
			(start -0.508 -0.9398)
			(end -0.508 0.9398)
			(stroke
				(width 0.1524)
				(type default)
			)
			(layer "F.SilkS")
		)
		(fp_line
			(start 0.508 -0.9398)
			(end -0.508 -0.9398)
			(stroke
				(width 0.1524)
				(type default)
			)
			(layer "F.SilkS")
		)
		(fp_rect
			(start -0.508 0.9398)
			(end 0.508 -0.9398)
			(stroke
				(width 0)
				(type default)
			)
			(fill no)
			(layer "F.CrtYd")
		)
		(fp_rect
			(start -0.508 0.9398)
			(end 0.508 -0.9398)
			(stroke
				(width 0)
				(type default)
			)
			(fill no)
			(layer "F.Fab")
		)
		(pad "1" smd custom
			(at 0 -0.4445)
			(size 0.1397 0.1397)
			(layers "F.Cu" "F.Mask" "F.Paste")
			(net "P3V3")
			(options
				(clearance outline)
				(anchor circle)
			)
			(primitives
				(gr_poly
					(pts
						(arc
							(start -0.1778 -0.2794)
							(mid -0.249642 -0.249642)
							(end -0.2794 -0.1778)
						)
						(arc
							(start -0.2794 0.1778)
							(mid -0.249642 0.249642)
							(end -0.1778 0.2794)
						)
						(arc
							(start 0.1778 0.2794)
							(mid 0.249642 0.249642)
							(end 0.2794 0.1778)
						)
						(arc
							(start 0.2794 -0.1778)
							(mid 0.249642 -0.249642)
							(end 0.1778 -0.2794)
						)
					)
					(width 0)
					(fill yes)
				)
			)
		)
		(pad "2" smd custom
			(at 0 0.4445)
			(size 0.1397 0.1397)
			(layers "F.Cu" "F.Mask" "F.Paste")
			(net "SAS2X28_A_HDD8_FLT")
			(options
				(clearance outline)
				(anchor circle)
			)
			(primitives
				(gr_poly
					(pts
						(arc
							(start -0.1778 -0.2794)
							(mid -0.249642 -0.249642)
							(end -0.2794 -0.1778)
						)
						(arc
							(start -0.2794 0.1778)
							(mid -0.249642 0.249642)
							(end -0.1778 0.2794)
						)
						(arc
							(start 0.1778 0.2794)
							(mid 0.249642 0.249642)
							(end 0.2794 0.1778)
						)
						(arc
							(start 0.2794 -0.1778)
							(mid 0.249642 -0.249642)
							(end 0.1778 -0.2794)
						)
					)
					(width 0)
					(fill yes)
				)
			)
		)
	)
	(footprint ""
		(layer "F.Cu")
		(at 207.009746 -42.4307 -90)
		(property "Reference" "R339"
			(at 0 0 270)
			(layer "F.SilkS")
			(hide yes)
			(effects
				(font
					(size 1.27 1.27)
				)
			)
		)
		(property "Value" "4K7R2J-2-GP"
			(at 0.064008 -3.993896 270)
			(unlocked yes)
			(layer "F.Fab")
			(hide yes)
			(effects
				(font
					(size 1.016 1.016)
					(thickness 0.1524)
				)
			)
		)
		(property "Device Type" "R402H16"
			(at 0.064008 -5.517896 270)
			(unlocked yes)
			(layer "F.Fab")
			(hide yes)
			(effects
				(font
					(size 1.016 1.016)
					(thickness 0.1524)
				)
			)
		)
		(duplicate_pad_numbers_are_jumpers no)
		(fp_line
			(start -0.508 -0.9398)
			(end -0.508 0.9398)
			(stroke
				(width 0.1524)
				(type default)
			)
			(layer "F.SilkS")
		)
		(fp_line
			(start 0.508 -0.9398)
			(end -0.508 -0.9398)
			(stroke
				(width 0.1524)
				(type default)
			)
			(layer "F.SilkS")
		)
		(fp_rect
			(start -0.508 0.9398)
			(end 0.508 -0.9398)
			(stroke
				(width 0)
				(type default)
			)
			(fill no)
			(layer "F.CrtYd")
		)
		(fp_rect
			(start -0.508 0.9398)
			(end 0.508 -0.9398)
			(stroke
				(width 0)
				(type default)
			)
			(fill no)
			(layer "F.Fab")
		)
		(pad "1" smd custom
			(at 0 -0.4445 270)
			(size 0.1397 0.1397)
			(layers "F.Cu" "F.Mask" "F.Paste")
			(net "I2C_B_TMP4_A2")
			(options
				(clearance outline)
				(anchor circle)
			)
			(primitives
				(gr_poly
					(pts
						(arc
							(start -0.1778 -0.2794)
							(mid -0.249642 -0.249642)
							(end -0.2794 -0.1778)
						)
						(arc
							(start -0.2794 0.1778)
							(mid -0.249642 0.249642)
							(end -0.1778 0.2794)
						)
						(arc
							(start 0.1778 0.2794)
							(mid 0.249642 0.249642)
							(end 0.2794 0.1778)
						)
						(arc
							(start 0.2794 -0.1778)
							(mid 0.249642 -0.249642)
							(end 0.1778 -0.2794)
						)
					)
					(width 0)
					(fill yes)
				)
			)
		)
		(pad "2" smd custom
			(at 0 0.4445 270)
			(size 0.1397 0.1397)
			(layers "F.Cu" "F.Mask" "F.Paste")
			(net "GND")
			(options
				(clearance outline)
				(anchor circle)
			)
			(primitives
				(gr_poly
					(pts
						(arc
							(start -0.1778 -0.2794)
							(mid -0.249642 -0.249642)
							(end -0.2794 -0.1778)
						)
						(arc
							(start -0.2794 0.1778)
							(mid -0.249642 0.249642)
							(end -0.1778 0.2794)
						)
						(arc
							(start 0.1778 0.2794)
							(mid 0.249642 0.249642)
							(end 0.2794 0.1778)
						)
						(arc
							(start 0.2794 -0.1778)
							(mid 0.249642 -0.249642)
							(end 0.1778 -0.2794)
						)
					)
					(width 0)
					(fill yes)
				)
			)
		)
	)
	(footprint ""
		(layer "F.Cu")
		(at 197.611746 -82.9437 -90)
		(property "Reference" "R440"
			(at 0 0 270)
			(layer "F.SilkS")
			(hide yes)
			(effects
				(font
					(size 1.27 1.27)
				)
			)
		)
		(property "Value" "4K7R2J-2-GP"
			(at 0.064008 -3.993896 270)
			(unlocked yes)
			(layer "F.Fab")
			(hide yes)
			(effects
				(font
					(size 1.016 1.016)
					(thickness 0.1524)
				)
			)
		)
		(property "Device Type" "R402H16"
			(at 0.064008 -5.517896 270)
			(unlocked yes)
			(layer "F.Fab")
			(hide yes)
			(effects
				(font
					(size 1.016 1.016)
					(thickness 0.1524)
				)
			)
		)
		(duplicate_pad_numbers_are_jumpers no)
		(fp_line
			(start -0.508 -0.9398)
			(end -0.508 0.9398)
			(stroke
				(width 0.1524)
				(type default)
			)
			(layer "F.SilkS")
		)
		(fp_line
			(start 0.508 -0.9398)
			(end -0.508 -0.9398)
			(stroke
				(width 0.1524)
				(type default)
			)
			(layer "F.SilkS")
		)
		(fp_rect
			(start -0.508 0.9398)
			(end 0.508 -0.9398)
			(stroke
				(width 0)
				(type default)
			)
			(fill no)
			(layer "F.CrtYd")
		)
		(fp_rect
			(start -0.508 0.9398)
			(end 0.508 -0.9398)
			(stroke
				(width 0)
				(type default)
			)
			(fill no)
			(layer "F.Fab")
		)
		(pad "1" smd custom
			(at 0 -0.4445 270)
			(size 0.1397 0.1397)
			(layers "F.Cu" "F.Mask" "F.Paste")
			(net "P3V3")
			(options
				(clearance outline)
				(anchor circle)
			)
			(primitives
				(gr_poly
					(pts
						(arc
							(start -0.1778 -0.2794)
							(mid -0.249642 -0.249642)
							(end -0.2794 -0.1778)
						)
						(arc
							(start -0.2794 0.1778)
							(mid -0.249642 0.249642)
							(end -0.1778 0.2794)
						)
						(arc
							(start 0.1778 0.2794)
							(mid 0.249642 0.249642)
							(end 0.2794 0.1778)
						)
						(arc
							(start 0.2794 -0.1778)
							(mid 0.249642 -0.249642)
							(end 0.1778 -0.2794)
						)
					)
					(width 0)
					(fill yes)
				)
			)
		)
		(pad "2" smd custom
			(at 0 0.4445 270)
			(size 0.1397 0.1397)
			(layers "F.Cu" "F.Mask" "F.Paste")
			(net "SAS_EXP_A_PWR4")
			(options
				(clearance outline)
				(anchor circle)
			)
			(primitives
				(gr_poly
					(pts
						(arc
							(start -0.1778 -0.2794)
							(mid -0.249642 -0.249642)
							(end -0.2794 -0.1778)
						)
						(arc
							(start -0.2794 0.1778)
							(mid -0.249642 0.249642)
							(end -0.1778 0.2794)
						)
						(arc
							(start 0.1778 0.2794)
							(mid 0.249642 0.249642)
							(end 0.2794 0.1778)
						)
						(arc
							(start 0.2794 -0.1778)
							(mid 0.249642 -0.249642)
							(end 0.1778 -0.2794)
						)
					)
					(width 0)
					(fill yes)
				)
			)
		)
	)
)
